# BASEBOARD_FAB2 (Tioga Pass) — schematic netlist excerpt (pin names and nets, part order shuffled) for the footprints in the layout excerpt that follows; sources: Cadence DE-HDL packaged netlist, KiCad conversion of Wiwynn_Tioga_Pass_MB.brd

EU7A1  IR354XX  IR35411 IC  pkg SM  page 219
  VOS  = PVDDQ_DEF
  LGND  = GND
  VCC  = VR_PVDDQ_DEF_PH1_VCIN
  VDRV  = P5V_STBY
  PGND(0)  = GND
  GL(0)  = TP_PVDDQ_DEF_PH1_GL_0
  PGND(1)  = GND
  SW  = VR_PVDDQ_DEF_PH1_SW
  VIN(0)  = VR_FET_SW_P12V_STBY_PVDDQ_DEF
  VIN(1)  = VR_FET_SW_P12V_STBY_PVDDQ_DEF
  NC  = NC
  PHASE  = VR_PVDDQ_DEF_PH1_PHASE
  BOOST  = VR_PVDDQ_DEF_PH1_BOOT_R
  PWM  = VR_PVDDQ_DEF_PWM1
  EN  = P5V_STBY
  TOUT_FLT  = A_TSENSE_PVDDQ_DEF
  OCSET  = VR_PVDDQ_DEF_PH1_OCSET
  IOUT  = ISENSE_PVDDQ_DEF_PH1_IMON
  REFIN  = VR_PVDDQ_DEF_AIREF1
  PGND(2)  = GND
  GL(1)  = TP_PVDDQ_DEF_PH1_GL_1

(kicad_pcb
	(version 20260206)
	(generator "pcbnew")
	(generator_version "10.0")
	(general
		(thickness 1.6)
		(legacy_teardrops no)
	)
	(paper "A4")
	(title_block
		(title "Wiwynn_Tioga_Pass_MB.brd")
		(comment 1 "Tioga Pass / footprints 1778-1778 of 4770")
	)
	(layers
		(0 "F.Cu" signal "TOP")
		(4 "In1.Cu" signal "L2GND")
		(6 "In2.Cu" signal "L3")
		(8 "In3.Cu" signal "L4GND")
		(10 "In4.Cu" signal "L5")
		(12 "In5.Cu" signal "L6GND")
		(14 "In6.Cu" signal "L7VCC")
		(16 "In7.Cu" signal "L8VCC")
		(18 "In8.Cu" signal "L9GND")
		(20 "In9.Cu" signal "L10")
		(22 "In10.Cu" signal "L11GND")
		(24 "In11.Cu" signal "L12")
		(26 "In12.Cu" signal "L13GND")
		(2 "B.Cu" signal "BOTTOM")
		(9 "F.Adhes" user "F.Adhesive")
		(11 "B.Adhes" user "B.Adhesive")
		(13 "F.Paste" user "Package Geometry/Pastemask Top")
		(15 "B.Paste" user "Package Geometry/Pastemask Bottom")
		(5 "F.SilkS" user "Ref Des/Silkscreen Top")
		(7 "B.SilkS" user "Ref Des/Silkscreen Bottom")
		(1 "F.Mask" user "Board Geometry/Soldermask Top")
		(3 "B.Mask" user "Board Geometry/Soldermask Bottom")
		(17 "Dwgs.User" user "User.Drawings")
		(19 "Cmts.User" user "User.Comments")
		(21 "Eco1.User" user "User.Eco1")
		(23 "Eco2.User" user "User.Eco2")
		(25 "Edge.Cuts" user "Board Geometry/Outline")
		(27 "Margin" user)
		(31 "F.CrtYd" user "Package Geometry/Place Bound Top")
		(29 "B.CrtYd" user "Package Geometry/Place Bound Bottom")
		(35 "F.Fab" user "Ref Des/Assembly Top")
		(33 "B.Fab" user "Ref Des/Assembly Bottom")
	)
	(footprint ""
		(layer "F.Cu")
		(at 347.462094 -153.218642 -90)
		(property "Reference" "EU7A1"
			(at 3.410712 2.733294 0)
			(unlocked yes)
			(layer "F.SilkS")
			(effects
				(font
					(size 0.7874 0.5842)
					(thickness 0.1524)
				)
			)
		)
		(property "Value" ""
			(at 0 0 270)
			(layer "F.Fab")
			(effects
				(font
					(size 1.27 1.27)
				)
			)
		)
		(duplicate_pad_numbers_are_jumpers no)
		(fp_line
			(start -3.0099 3.429)
			(end -3.0099 -3.5052)
			(stroke
				(width 0.1524)
				(type default)
			)
			(layer "F.SilkS")
		)
		(fp_line
			(start 2.9718 3.429)
			(end -3.0099 3.429)
			(stroke
				(width 0.1524)
				(type default)
			)
			(layer "F.SilkS")
		)
		(fp_line
			(start -3.0099 -3.5052)
			(end 2.9718 -3.5052)
			(stroke
				(width 0.1524)
				(type default)
			)
			(layer "F.SilkS")
		)
		(fp_line
			(start 2.9718 -3.5052)
			(end 2.9718 3.429)
			(stroke
				(width 0.1524)
				(type default)
			)
			(layer "F.SilkS")
		)
		(fp_circle
			(center -3.057398 -2.678684)
			(end -3.057398 -2.805684)
			(stroke
				(width 0.254)
				(type default)
			)
			(fill no)
			(layer "F.SilkS")
		)
		(fp_poly
			(pts
				(xy -2.9972 -3.4925) (xy -2.9972 -2.6924) (xy -2.1971 -3.4925)
			)
			(stroke
				(width 0)
				(type default)
			)
			(fill yes)
			(layer "F.SilkS")
		)
		(fp_poly
			(pts
				(xy -2.549906 -3.050032) (xy -2.549906 3.050032) (xy 2.549906 3.050032) (xy 2.549906 -3.050032)
			)
			(stroke
				(width 0)
				(type default)
			)
			(fill no)
			(layer "F.CrtYd")
		)
		(fp_line
			(start -2.549906 3.050032)
			(end -2.549906 -3.050032)
			(stroke
				(width 0.1)
				(type default)
			)
			(layer "F.Fab")
		)
		(fp_line
			(start 2.549906 3.050032)
			(end -2.549906 3.050032)
			(stroke
				(width 0.1)
				(type default)
			)
			(layer "F.Fab")
		)
		(fp_line
			(start -2.549906 -3.050032)
			(end 2.549906 -3.050032)
			(stroke
				(width 0.1)
				(type default)
			)
			(layer "F.Fab")
		)
		(fp_line
			(start 2.549906 -3.050032)
			(end 2.549906 3.050032)
			(stroke
				(width 0.1)
				(type default)
			)
			(layer "F.Fab")
		)
		(fp_circle
			(center -3.057398 -2.678684)
			(end -3.057398 -2.805684)
			(stroke
				(width 0.254)
				(type default)
			)
			(fill no)
			(layer "F.Fab")
		)
		(pad "1" smd rect
			(at -2.39522 -2.279904 270)
			(size 0.7112 0.254)
			(layers "F.Cu" "F.Mask" "F.Paste")
			(net "PVDDQ_DEF")
		)
		(pad "2" smd rect
			(at -2.39522 -1.83007 270)
			(size 0.7112 0.254)
			(layers "F.Cu" "F.Mask" "F.Paste")
			(net "GND")
		)
		(pad "3" smd rect
			(at -2.39522 -1.379982 270)
			(size 0.7112 0.254)
			(layers "F.Cu" "F.Mask" "F.Paste")
			(net "VR_PVDDQ_DEF_PH1_VCIN")
		)
		(pad "4" smd rect
			(at -2.39522 -0.929894 270)
			(size 0.7112 0.254)
			(layers "F.Cu" "F.Mask" "F.Paste")
			(net "P5V_STBY")
		)
		(pad "5" smd rect
			(at -2.39522 -0.48006 270)
			(size 0.7112 0.254)
			(layers "F.Cu" "F.Mask" "F.Paste")
			(net "GND")
		)
		(pad "6" smd rect
			(at -2.39522 -0.029972 270)
			(size 0.7112 0.254)
			(layers "F.Cu" "F.Mask" "F.Paste")
			(net "TP_PVDDQ_DEF_PH1_GL_0")
		)
		(pad "7" smd custom
			(at 0.016764 1.145032 270)
			(size 0.53975 0.53975)
			(layers "F.Cu" "F.Mask" "F.Paste")
			(net "GND")
			(options
				(clearance outline)
				(anchor circle)
			)
			(primitives
				(gr_poly
					(pts
						(xy -2.7051 1.0795) (xy -2.7051 -0.3683) (xy -0.9271 -0.3683) (xy -0.9271 -1.0795) (xy 2.7051 -1.0795)
						(xy 2.7051 1.0795)
					)
					(width 0)
					(fill yes)
				)
			)
		)
		(pad "10" smd rect
			(at -0.008382 2.874772 270)
			(size 4.3434 0.6096)
			(layers "F.Cu" "F.Mask" "F.Paste")
			(net "VR_PVDDQ_DEF_PH1_SW")
		)
		(pad "25" smd rect
			(at 1.548384 -1.283208 270)
			(size 2.3368 2.0066)
			(layers "F.Cu" "F.Mask" "F.Paste")
			(net "VR_FET_SW_P12V_STBY_PVDDQ_DEF")
		)
		(pad "30" smd rect
			(at 2.050034 -2.895092 270)
			(size 0.254 0.7112)
			(layers "F.Cu" "F.Mask" "F.Paste")
			(net "VR_FET_SW_P12V_STBY_PVDDQ_DEF")
		)
		(pad "31" smd rect
			(at 1.599946 -2.895092 270)
			(size 0.254 0.7112)
			(layers "F.Cu" "F.Mask" "F.Paste")
			(net "Net_370")
		)
		(pad "32" smd rect
			(at 1.150112 -2.895092 270)
			(size 0.254 0.7112)
			(layers "F.Cu" "F.Mask" "F.Paste")
			(net "VR_PVDDQ_DEF_PH1_PHASE")
		)
		(pad "33" smd rect
			(at 0.700024 -2.895092 270)
			(size 0.254 0.7112)
			(layers "F.Cu" "F.Mask" "F.Paste")
			(net "VR_PVDDQ_DEF_PH1_BOOT_R")
		)
		(pad "34" smd rect
			(at 0.249936 -2.895092 270)
			(size 0.254 0.7112)
			(layers "F.Cu" "F.Mask" "F.Paste")
			(net "VR_PVDDQ_DEF_PWM1")
		)
		(pad "35" smd rect
			(at -0.199898 -2.895092 270)
			(size 0.254 0.7112)
			(layers "F.Cu" "F.Mask" "F.Paste")
			(net "P5V_STBY")
		)
		(pad "36" smd rect
			(at -0.649986 -2.895092 270)
			(size 0.254 0.7112)
			(layers "F.Cu" "F.Mask" "F.Paste")
			(net "A_TSENSE_PVDDQ_DEF")
		)
		(pad "37" smd rect
			(at -1.100074 -2.895092 270)
			(size 0.254 0.7112)
			(layers "F.Cu" "F.Mask" "F.Paste")
			(net "VR_PVDDQ_DEF_PH1_OCSET")
		)
		(pad "38" smd rect
			(at -1.549908 -2.895092 270)
			(size 0.254 0.7112)
			(layers "F.Cu" "F.Mask" "F.Paste")
			(net "ISENSE_PVDDQ_DEF_PH1_IMON")
		)
		(pad "39" smd rect
			(at -1.999996 -2.895092 270)
			(size 0.254 0.7112)
			(layers "F.Cu" "F.Mask" "F.Paste")
			(net "VR_PVDDQ_DEF_AIREF1")
		)
		(pad "40" smd rect
			(at -0.871728 -1.283208 270)
			(size 1.8034 2.0066)
			(layers "F.Cu" "F.Mask" "F.Paste")
			(net "GND")
		)
		(pad "41" smd rect
			(at -1.533906 0.247904 270)
			(size 0.508 0.3556)
			(layers "F.Cu" "F.Mask" "F.Paste")
			(net "TP_PVDDQ_DEF_PH1_GL_1")
		)
	)
)
